(kicad_pcb
	(version 20260206)
	(generator "pcbnew")
	(generator_version "10.0")
	(general
		(thickness 1.6)
		(legacy_teardrops no)
	)
	(paper "A4")
	(title_block
		(title "04192023_DAF0TMB3IC0_F0TG_MB_C_brd_V02_OCP.brd")
		(comment 1 "Grand Teton / footprint 2783 of 8354 (U26), pads 3447-3557 of 6102")
	)
	(layers
		(0 "F.Cu" signal "TOP")
		(4 "In1.Cu" signal "GND")
		(6 "In2.Cu" signal "IN1")
		(8 "In3.Cu" signal "GND1")
		(10 "In4.Cu" signal "IN2")
		(12 "In5.Cu" signal "GND2")
		(14 "In6.Cu" signal "IN3")
		(16 "In7.Cu" signal "GND3")
		(18 "In8.Cu" signal "VCC")
		(20 "In9.Cu" signal "VCC1")
		(22 "In10.Cu" signal "GND4")
		(24 "In11.Cu" signal "IN4")
		(26 "In12.Cu" signal "GND5")
		(28 "In13.Cu" signal "IN5")
		(30 "In14.Cu" signal "GND6")
		(32 "In15.Cu" signal "IN6")
		(34 "In16.Cu" signal "GND7")
		(2 "B.Cu" signal "BOTTOM")
		(9 "F.Adhes" user "F.Adhesive")
		(11 "B.Adhes" user "B.Adhesive")
		(13 "F.Paste" user "Package Geometry/Pastemask Top")
		(15 "B.Paste" user "Package Geometry/Pastemask Bottom")
		(5 "F.SilkS" user "Ref Des/Silkscreen Top")
		(7 "B.SilkS" user "Ref Des/Silkscreen Bottom")
		(1 "F.Mask" user "Board Geometry/Soldermask Top")
		(3 "B.Mask" user "Board Geometry/Soldermask Bottom")
		(17 "Dwgs.User" user "User.Drawings")
		(19 "Cmts.User" user "User.Comments")
		(21 "Eco1.User" user "User.Eco1")
		(23 "Eco2.User" user "User.Eco2")
		(25 "Edge.Cuts" user "Board Geometry/Outline")
		(27 "Margin" user)
		(31 "F.CrtYd" user "Package Geometry/Place Bound Top")
		(29 "B.CrtYd" user "Package Geometry/Place Bound Bottom")
		(35 "F.Fab" user "Ref Des/Assembly Top")
		(33 "B.Fab" user "Ref Des/Assembly Bottom")
	)
	(footprint ""
		(layer "F.Cu")
		(at 111.927894 -258.880356 180)
		(property "Reference" "U26"
			(at -45.05579 -61.794136 0)
			(unlocked yes)
			(layer "F.SilkS")
			(effects
				(font
					(size 0.7874 0.5842)
					(thickness 0.1524)
				)
			)
		)
		(property "Value" ""
			(at 0 0 180)
			(layer "F.Fab")
			(effects
				(font
					(size 1.27 1.27)
				)
			)
		)
		(duplicate_pad_numbers_are_jumpers no)
		(pad "CJ66" smd circle
			(at 25.699974 20.610068 180)
			(size 0.450088 0.450088)
			(layers "F.Cu" "F.Mask" "F.Paste")
			(net "M_F_CPU1_SB_DQ<9>")
		)
		(pad "CJ67" smd circle
			(at 26.640028 20.610068 180)
			(size 0.450088 0.450088)
			(layers "F.Cu" "F.Mask" "F.Paste")
			(net "M_F_CPU1_SB_DQ<10>")
		)
		(pad "CJ68" smd circle
			(at 27.580082 20.610068 180)
			(size 0.450088 0.450088)
			(layers "F.Cu" "F.Mask" "F.Paste")
			(net "GND")
		)
		(pad "CJ69" smd circle
			(at 28.519882 20.610068 180)
			(size 0.450088 0.450088)
			(layers "F.Cu" "F.Mask" "F.Paste")
			(net "M_E_CPU1_SB_DQ<9>")
		)
		(pad "CJ70" smd circle
			(at 29.459936 20.610068 180)
			(size 0.450088 0.450088)
			(layers "F.Cu" "F.Mask" "F.Paste")
			(net "GND")
		)
		(pad "CJ71" smd circle
			(at 30.39999 20.610068 180)
			(size 0.450088 0.450088)
			(layers "F.Cu" "F.Mask" "F.Paste")
			(net "M_E_CPU1_SB_DQ<10>")
		)
		(pad "CJ72" smd circle
			(at 31.340044 20.610068 180)
			(size 0.450088 0.450088)
			(layers "F.Cu" "F.Mask" "F.Paste")
			(net "GND")
		)
		(pad "CJ73" smd circle
			(at 32.280098 20.610068 180)
			(size 0.450088 0.450088)
			(layers "F.Cu" "F.Mask" "F.Paste")
			(net "M_A_CPU1_SB_DQ<9>")
		)
		(pad "CJ74" smd circle
			(at 33.219898 20.610068 180)
			(size 0.450088 0.450088)
			(layers "F.Cu" "F.Mask" "F.Paste")
			(net "M_A_CPU1_SB_DQ<10>")
		)
		(pad "CJ75" smd circle
			(at 34.159952 20.610068 180)
			(size 0.450088 0.450088)
			(layers "F.Cu" "F.Mask" "F.Paste")
			(net "GND")
		)
		(pad "CK2" smd circle
			(at -33.990026 21.420074 180)
			(size 0.450088 0.450088)
			(layers "F.Cu" "F.Mask" "F.Paste")
			(net "M_G_CPU1_SB_DQS_DP<1>")
		)
		(pad "CK3" smd circle
			(at -33.049972 21.420074 180)
			(size 0.450088 0.450088)
			(layers "F.Cu" "F.Mask" "F.Paste")
			(net "GND")
		)
		(pad "CK4" smd circle
			(at -32.109918 21.420074 180)
			(size 0.450088 0.450088)
			(layers "F.Cu" "F.Mask" "F.Paste")
			(net "M_G_CPU1_SB_DQ<11>")
		)
		(pad "CK5" smd circle
			(at -31.170118 21.420074 180)
			(size 0.450088 0.450088)
			(layers "F.Cu" "F.Mask" "F.Paste")
			(net "PVDD11_S3_P1")
		)
		(pad "CK6" smd circle
			(at -30.230064 21.420074 180)
			(size 0.450088 0.450088)
			(layers "F.Cu" "F.Mask" "F.Paste")
			(net "M_K_CPU1_SB_DQS_DP<1>")
		)
		(pad "CK7" smd circle
			(at -29.29001 21.420074 180)
			(size 0.450088 0.450088)
			(layers "F.Cu" "F.Mask" "F.Paste")
			(net "M_K_CPU1_SB_DQ<11>")
		)
		(pad "CK8" smd circle
			(at -28.349956 21.420074 180)
			(size 0.450088 0.450088)
			(layers "F.Cu" "F.Mask" "F.Paste")
			(net "GND")
		)
		(pad "CK9" smd circle
			(at -27.409902 21.420074 180)
			(size 0.450088 0.450088)
			(layers "F.Cu" "F.Mask" "F.Paste")
			(net "M_L_CPU1_SB_DQS_DP<1>")
		)
		(pad "CK10" smd circle
			(at -26.470102 21.420074 180)
			(size 0.450088 0.450088)
			(layers "F.Cu" "F.Mask" "F.Paste")
			(net "GND")
		)
		(pad "CK11" smd circle
			(at -25.530048 21.420074 180)
			(size 0.450088 0.450088)
			(layers "F.Cu" "F.Mask" "F.Paste")
			(net "M_L_CPU1_SB_DQ<11>")
		)
		(pad "CK12" smd circle
			(at -24.589994 21.420074 180)
			(size 0.450088 0.450088)
			(layers "F.Cu" "F.Mask" "F.Paste")
			(net "PVDD11_S3_P1")
		)
		(pad "CK13" smd circle
			(at -23.64994 21.420074 180)
			(size 0.450088 0.450088)
			(layers "F.Cu" "F.Mask" "F.Paste")
			(net "M_H_CPU1_SB_DQS_DP<1>")
		)
		(pad "CK14" smd circle
			(at -22.709886 21.420074 180)
			(size 0.450088 0.450088)
			(layers "F.Cu" "F.Mask" "F.Paste")
			(net "M_H_CPU1_SB_DQ<11>")
		)
		(pad "CK15" smd circle
			(at -21.770086 21.420074 180)
			(size 0.450088 0.450088)
			(layers "F.Cu" "F.Mask" "F.Paste")
			(net "GND")
		)
		(pad "CK16" smd circle
			(at -20.830032 21.420074 180)
			(size 0.450088 0.450088)
			(layers "F.Cu" "F.Mask" "F.Paste")
			(net "M_J_CPU1_SB_DQS_DP<1>")
		)
		(pad "CK17" smd circle
			(at -19.889978 21.420074 180)
			(size 0.450088 0.450088)
			(layers "F.Cu" "F.Mask" "F.Paste")
			(net "GND")
		)
		(pad "CK18" smd circle
			(at -18.949924 21.420074 180)
			(size 0.450088 0.450088)
			(layers "F.Cu" "F.Mask" "F.Paste")
			(net "M_J_CPU1_SB_DQ<11>")
		)
		(pad "CK19" smd circle
			(at -18.010124 21.420074 180)
			(size 0.450088 0.450088)
			(layers "F.Cu" "F.Mask" "F.Paste")
			(net "PVDD11_S3_P1")
		)
		(pad "CK20" smd circle
			(at -17.07007 21.420074 180)
			(size 0.450088 0.450088)
			(layers "F.Cu" "F.Mask" "F.Paste")
			(net "M_I_CPU1_SB_DQS_DP<1>")
		)
		(pad "CK21" smd circle
			(at -16.130016 21.420074 180)
			(size 0.450088 0.450088)
			(layers "F.Cu" "F.Mask" "F.Paste")
			(net "M_I_CPU1_SB_DQ<11>")
		)
		(pad "CK22" smd circle
			(at -15.189962 21.420074 180)
			(size 0.450088 0.450088)
			(layers "F.Cu" "F.Mask" "F.Paste")
			(net "GND")
		)
		(pad "CK23" smd circle
			(at -14.249908 21.420074 180)
			(size 0.450088 0.450088)
			(layers "F.Cu" "F.Mask" "F.Paste")
			(net "GND")
		)
		(pad "CK24" smd circle
			(at -13.310108 21.420074 180)
			(size 0.450088 0.450088)
			(layers "F.Cu" "F.Mask" "F.Paste")
			(net "GND")
		)
		(pad "CK25" smd circle
			(at -12.370054 21.420074 180)
			(size 0.450088 0.450088)
			(layers "F.Cu" "F.Mask" "F.Paste")
			(net "GND")
		)
		(pad "CK26" smd circle
			(at -11.43 21.420074 180)
			(size 0.450088 0.450088)
			(layers "F.Cu" "F.Mask" "F.Paste")
			(net "GND")
		)
		(pad "CK27" smd circle
			(at -10.489946 21.420074 180)
			(size 0.450088 0.450088)
			(layers "F.Cu" "F.Mask" "F.Paste")
			(net "GND")
		)
		(pad "CK28" smd circle
			(at -9.549892 21.420074 180)
			(size 0.450088 0.450088)
			(layers "F.Cu" "F.Mask" "F.Paste")
			(net "GND")
		)
		(pad "CK29" smd circle
			(at -8.610092 21.420074 180)
			(size 0.450088 0.450088)
			(layers "F.Cu" "F.Mask" "F.Paste")
			(net "TP_CPU1_TEST5_CCD9")
		)
		(pad "CK30" smd circle
			(at -7.670038 21.420074 180)
			(size 0.450088 0.450088)
			(layers "F.Cu" "F.Mask" "F.Paste")
			(net "TP_CPU1_TEST4_CCD9")
		)
		(pad "CK31" smd circle
			(at -6.729984 21.420074 180)
			(size 0.450088 0.450088)
			(layers "F.Cu" "F.Mask" "F.Paste")
			(net "GND")
		)
		(pad "CK32" smd circle
			(at -5.78993 21.420074 180)
			(size 0.450088 0.450088)
			(layers "F.Cu" "F.Mask" "F.Paste")
			(net "GND")
		)
		(pad "CK33" smd circle
			(at -4.849876 21.420074 180)
			(size 0.450088 0.450088)
			(layers "F.Cu" "F.Mask" "F.Paste")
			(net "GND")
		)
		(pad "CK34" smd circle
			(at -3.910076 21.420074 180)
			(size 0.450088 0.450088)
			(layers "F.Cu" "F.Mask" "F.Paste")
			(net "GND")
		)
		(pad "CK35" smd circle
			(at -2.970022 21.420074 180)
			(size 0.450088 0.450088)
			(layers "F.Cu" "F.Mask" "F.Paste")
			(net "PVDDCR_CPU1_P1")
		)
		(pad "CK36" smd circle
			(at -2.029968 21.420074 180)
			(size 0.450088 0.450088)
			(layers "F.Cu" "F.Mask" "F.Paste")
			(net "PVDDCR_CPU1_P1")
		)
		(pad "CK37" smd circle
			(at -1.089914 21.420074 180)
			(size 0.450088 0.450088)
			(layers "F.Cu" "F.Mask" "F.Paste")
			(net "GND")
		)
		(pad "CK39" smd circle
			(at 0.78994 21.420074 180)
			(size 0.450088 0.450088)
			(layers "F.Cu" "F.Mask" "F.Paste")
			(net "GND")
		)
		(pad "CK40" smd circle
			(at 1.729994 21.420074 180)
			(size 0.450088 0.450088)
			(layers "F.Cu" "F.Mask" "F.Paste")
			(net "PVDDCR_CPU1_P1")
		)
		(pad "CK41" smd circle
			(at 2.670048 21.420074 180)
			(size 0.450088 0.450088)
			(layers "F.Cu" "F.Mask" "F.Paste")
			(net "PVDDCR_CPU1_P1")
		)
		(pad "CK42" smd circle
			(at 3.610102 21.420074 180)
			(size 0.450088 0.450088)
			(layers "F.Cu" "F.Mask" "F.Paste")
			(net "GND")
		)
		(pad "CK43" smd circle
			(at 4.549902 21.420074 180)
			(size 0.450088 0.450088)
			(layers "F.Cu" "F.Mask" "F.Paste")
			(net "GND")
		)
		(pad "CK44" smd circle
			(at 5.489956 21.420074 180)
			(size 0.450088 0.450088)
			(layers "F.Cu" "F.Mask" "F.Paste")
			(net "GND")
		)
		(pad "CK45" smd circle
			(at 6.43001 21.420074 180)
			(size 0.450088 0.450088)
			(layers "F.Cu" "F.Mask" "F.Paste")
			(net "GND")
		)
		(pad "CK46" smd circle
			(at 7.370064 21.420074 180)
			(size 0.450088 0.450088)
			(layers "F.Cu" "F.Mask" "F.Paste")
			(net "TP_CPU1_TEST47_CCD2")
		)
		(pad "CK47" smd circle
			(at 8.310118 21.420074 180)
			(size 0.450088 0.450088)
			(layers "F.Cu" "F.Mask" "F.Paste")
			(net "TP_CPU1_TEST5_CCD10")
		)
		(pad "CK48" smd circle
			(at 9.249918 21.420074 180)
			(size 0.450088 0.450088)
			(layers "F.Cu" "F.Mask" "F.Paste")
			(net "GND")
		)
		(pad "CK49" smd circle
			(at 10.189972 21.420074 180)
			(size 0.450088 0.450088)
			(layers "F.Cu" "F.Mask" "F.Paste")
			(net "GND")
		)
		(pad "CK50" smd circle
			(at 11.130026 21.420074 180)
			(size 0.450088 0.450088)
			(layers "F.Cu" "F.Mask" "F.Paste")
			(net "GND")
		)
		(pad "CK51" smd circle
			(at 12.07008 21.420074 180)
			(size 0.450088 0.450088)
			(layers "F.Cu" "F.Mask" "F.Paste")
			(net "GND")
		)
		(pad "CK52" smd circle
			(at 13.00988 21.420074 180)
			(size 0.450088 0.450088)
			(layers "F.Cu" "F.Mask" "F.Paste")
			(net "GND")
		)
		(pad "CK53" smd circle
			(at 13.949934 21.420074 180)
			(size 0.450088 0.450088)
			(layers "F.Cu" "F.Mask" "F.Paste")
			(net "GND")
		)
		(pad "CK54" smd circle
			(at 14.889988 21.420074 180)
			(size 0.450088 0.450088)
			(layers "F.Cu" "F.Mask" "F.Paste")
			(net "GND")
		)
		(pad "CK55" smd circle
			(at 15.830042 21.420074 180)
			(size 0.450088 0.450088)
			(layers "F.Cu" "F.Mask" "F.Paste")
			(net "M_C_CPU1_SB_DQ<11>")
		)
		(pad "CK56" smd circle
			(at 16.770096 21.420074 180)
			(size 0.450088 0.450088)
			(layers "F.Cu" "F.Mask" "F.Paste")
			(net "M_C_CPU1_SB_DQS_DP<1>")
		)
		(pad "CK57" smd circle
			(at 17.709896 21.420074 180)
			(size 0.450088 0.450088)
			(layers "F.Cu" "F.Mask" "F.Paste")
			(net "PVDDIO_P1")
		)
		(pad "CK58" smd circle
			(at 18.64995 21.420074 180)
			(size 0.450088 0.450088)
			(layers "F.Cu" "F.Mask" "F.Paste")
			(net "M_D_CPU1_SB_DQ<11>")
		)
		(pad "CK59" smd circle
			(at 19.590004 21.420074 180)
			(size 0.450088 0.450088)
			(layers "F.Cu" "F.Mask" "F.Paste")
			(net "GND")
		)
		(pad "CK60" smd circle
			(at 20.530058 21.420074 180)
			(size 0.450088 0.450088)
			(layers "F.Cu" "F.Mask" "F.Paste")
			(net "M_D_CPU1_SB_DQS_DP<1>")
		)
		(pad "CK61" smd circle
			(at 21.470112 21.420074 180)
			(size 0.450088 0.450088)
			(layers "F.Cu" "F.Mask" "F.Paste")
			(net "GND")
		)
		(pad "CK62" smd circle
			(at 22.409912 21.420074 180)
			(size 0.450088 0.450088)
			(layers "F.Cu" "F.Mask" "F.Paste")
			(net "M_B_CPU1_SB_DQ<11>")
		)
		(pad "CK63" smd circle
			(at 23.349966 21.420074 180)
			(size 0.450088 0.450088)
			(layers "F.Cu" "F.Mask" "F.Paste")
			(net "M_B_CPU1_SB_DQS_DP<1>")
		)
		(pad "CK64" smd circle
			(at 24.29002 21.420074 180)
			(size 0.450088 0.450088)
			(layers "F.Cu" "F.Mask" "F.Paste")
			(net "PVDDIO_P1")
		)
		(pad "CK65" smd circle
			(at 25.230074 21.420074 180)
			(size 0.450088 0.450088)
			(layers "F.Cu" "F.Mask" "F.Paste")
			(net "M_F_CPU1_SB_DQ<11>")
		)
		(pad "CK66" smd circle
			(at 26.170128 21.420074 180)
			(size 0.450088 0.450088)
			(layers "F.Cu" "F.Mask" "F.Paste")
			(net "GND")
		)
		(pad "CK67" smd circle
			(at 27.109928 21.420074 180)
			(size 0.450088 0.450088)
			(layers "F.Cu" "F.Mask" "F.Paste")
			(net "M_F_CPU1_SB_DQS_DP<1>")
		)
		(pad "CK68" smd circle
			(at 28.049982 21.420074 180)
			(size 0.450088 0.450088)
			(layers "F.Cu" "F.Mask" "F.Paste")
			(net "GND")
		)
		(pad "CK69" smd circle
			(at 28.990036 21.420074 180)
			(size 0.450088 0.450088)
			(layers "F.Cu" "F.Mask" "F.Paste")
			(net "M_E_CPU1_SB_DQ<11>")
		)
		(pad "CK70" smd circle
			(at 29.93009 21.420074 180)
			(size 0.450088 0.450088)
			(layers "F.Cu" "F.Mask" "F.Paste")
			(net "M_E_CPU1_SB_DQS_DP<1>")
		)
		(pad "CK71" smd circle
			(at 30.86989 21.420074 180)
			(size 0.450088 0.450088)
			(layers "F.Cu" "F.Mask" "F.Paste")
			(net "PVDDIO_P1")
		)
		(pad "CK72" smd circle
			(at 31.809944 21.420074 180)
			(size 0.450088 0.450088)
			(layers "F.Cu" "F.Mask" "F.Paste")
			(net "M_A_CPU1_SB_DQ<11>")
		)
		(pad "CK73" smd circle
			(at 32.749998 21.420074 180)
			(size 0.450088 0.450088)
			(layers "F.Cu" "F.Mask" "F.Paste")
			(net "GND")
		)
		(pad "CK74" smd circle
			(at 33.690052 21.420074 180)
			(size 0.450088 0.450088)
			(layers "F.Cu" "F.Mask" "F.Paste")
			(net "M_A_CPU1_SB_DQS_DP<1>")
		)
		(pad "CL1" smd circle
			(at -34.459926 22.23008 180)
			(size 0.450088 0.450088)
			(layers "F.Cu" "F.Mask" "F.Paste")
			(net "GND")
		)
		(pad "CL2" smd circle
			(at -33.519872 22.23008 180)
			(size 0.450088 0.450088)
			(layers "F.Cu" "F.Mask" "F.Paste")
			(net "M_G_CPU1_SB_DQS_DN<1>")
		)
		(pad "CL3" smd circle
			(at -32.580072 22.23008 180)
			(size 0.450088 0.450088)
			(layers "F.Cu" "F.Mask" "F.Paste")
			(net "M_G_CPU1_SB_DQS_DN<6>")
		)
		(pad "CL4" smd circle
			(at -31.640018 22.23008 180)
			(size 0.450088 0.450088)
			(layers "F.Cu" "F.Mask" "F.Paste")
			(net "GND")
		)
		(pad "CL5" smd circle
			(at -30.699964 22.23008 180)
			(size 0.450088 0.450088)
			(layers "F.Cu" "F.Mask" "F.Paste")
			(net "M_K_CPU1_SB_DQS_DN<1>")
		)
		(pad "CL6" smd circle
			(at -29.75991 22.23008 180)
			(size 0.450088 0.450088)
			(layers "F.Cu" "F.Mask" "F.Paste")
			(net "GND")
		)
		(pad "CL7" smd circle
			(at -28.82011 22.23008 180)
			(size 0.450088 0.450088)
			(layers "F.Cu" "F.Mask" "F.Paste")
			(net "M_K_CPU1_SB_DQS_DN<6>")
		)
		(pad "CL8" smd circle
			(at -27.880056 22.23008 180)
			(size 0.450088 0.450088)
			(layers "F.Cu" "F.Mask" "F.Paste")
			(net "GND")
		)
		(pad "CL9" smd circle
			(at -26.940002 22.23008 180)
			(size 0.450088 0.450088)
			(layers "F.Cu" "F.Mask" "F.Paste")
			(net "M_L_CPU1_SB_DQS_DN<1>")
		)
		(pad "CL10" smd circle
			(at -25.999948 22.23008 180)
			(size 0.450088 0.450088)
			(layers "F.Cu" "F.Mask" "F.Paste")
			(net "M_L_CPU1_SB_DQS_DN<6>")
		)
		(pad "CL11" smd circle
			(at -25.059894 22.23008 180)
			(size 0.450088 0.450088)
			(layers "F.Cu" "F.Mask" "F.Paste")
			(net "GND")
		)
		(pad "CL12" smd circle
			(at -24.120094 22.23008 180)
			(size 0.450088 0.450088)
			(layers "F.Cu" "F.Mask" "F.Paste")
			(net "M_H_CPU1_SB_DQS_DN<1>")
		)
		(pad "CL13" smd circle
			(at -23.18004 22.23008 180)
			(size 0.450088 0.450088)
			(layers "F.Cu" "F.Mask" "F.Paste")
			(net "GND")
		)
		(pad "CL14" smd circle
			(at -22.239986 22.23008 180)
			(size 0.450088 0.450088)
			(layers "F.Cu" "F.Mask" "F.Paste")
			(net "M_H_CPU1_SB_DQS_DN<6>")
		)
		(pad "CL15" smd circle
			(at -21.299932 22.23008 180)
			(size 0.450088 0.450088)
			(layers "F.Cu" "F.Mask" "F.Paste")
			(net "GND")
		)
		(pad "CL16" smd circle
			(at -20.359878 22.23008 180)
			(size 0.450088 0.450088)
			(layers "F.Cu" "F.Mask" "F.Paste")
			(net "M_J_CPU1_SB_DQS_DN<1>")
		)
		(pad "CL17" smd circle
			(at -19.420078 22.23008 180)
			(size 0.450088 0.450088)
			(layers "F.Cu" "F.Mask" "F.Paste")
			(net "M_J_CPU1_SB_DQS_DN<6>")
		)
		(pad "CL18" smd circle
			(at -18.480024 22.23008 180)
			(size 0.450088 0.450088)
			(layers "F.Cu" "F.Mask" "F.Paste")
			(net "GND")
		)
		(pad "CL19" smd circle
			(at -17.53997 22.23008 180)
			(size 0.450088 0.450088)
			(layers "F.Cu" "F.Mask" "F.Paste")
			(net "M_I_CPU1_SB_DQS_DN<1>")
		)
		(pad "CL20" smd circle
			(at -16.599916 22.23008 180)
			(size 0.450088 0.450088)
			(layers "F.Cu" "F.Mask" "F.Paste")
			(net "GND")
		)
		(pad "CL21" smd circle
			(at -15.660116 22.23008 180)
			(size 0.450088 0.450088)
			(layers "F.Cu" "F.Mask" "F.Paste")
			(net "M_I_CPU1_SB_DQS_DN<6>")
		)
		(pad "CL22" smd circle
			(at -14.720062 22.23008 180)
			(size 0.450088 0.450088)
			(layers "F.Cu" "F.Mask" "F.Paste")
			(net "GND")
		)
		(pad "CL23" smd circle
			(at -13.780008 22.23008 180)
			(size 0.450088 0.450088)
			(layers "F.Cu" "F.Mask" "F.Paste")
			(net "P5E_CPU1_P2_RX_DP<13>")
		)
		(pad "CL24" smd circle
			(at -12.839954 22.23008 180)
			(size 0.450088 0.450088)
			(layers "F.Cu" "F.Mask" "F.Paste")
			(net "P5E_CPU1_P2_RX_DN<13>")
		)
		(pad "CL25" smd circle
			(at -11.8999 22.23008 180)
			(size 0.450088 0.450088)
			(layers "F.Cu" "F.Mask" "F.Paste")
			(net "GND")
		)
		(pad "CL26" smd circle
			(at -10.9601 22.23008 180)
			(size 0.450088 0.450088)
			(layers "F.Cu" "F.Mask" "F.Paste")
			(net "P5E_CPU1_P2_RX_DP<9>")
		)
		(pad "CL27" smd circle
			(at -10.020046 22.23008 180)
			(size 0.450088 0.450088)
			(layers "F.Cu" "F.Mask" "F.Paste")
			(net "P5E_CPU1_P2_RX_DN<9>")
		)
		(pad "CL28" smd circle
			(at -9.079992 22.23008 180)
			(size 0.450088 0.450088)
			(layers "F.Cu" "F.Mask" "F.Paste")
			(net "GND")
		)
		(pad "CL29" smd circle
			(at -8.139938 22.23008 180)
			(size 0.450088 0.450088)
			(layers "F.Cu" "F.Mask" "F.Paste")
			(net "PVDDCR_CPU1_P1")
		)
	)
)
